# S9S_MB_2U (Grand Teton) — schematic netlist excerpt (pin names and nets, part order shuffled) for the footprints in the layout excerpt that follows; sources: Cadence DE-HDL packaged netlist, KiCad conversion of 03242023_DA0F0TMBIJ0_F0T_Motherboard_J_brd_V01_OCP.brd

R1004  Q_RES  1K 1% CHIP  pkg 0402LF  page 127 : A = P3V3_AUX ; B = PU_PIROM_CPU1_SM_WP
R3182  Q_RES  10K 1% CHIP  pkg 0402LF  page 161 : A = P3V3_OCP_V3_2 ; B = IRQ_LVC3_OCP_V3_2_WAKE_N

(kicad_pcb
	(version 20260206)
	(generator "pcbnew")
	(generator_version "10.0")
	(general
		(thickness 1.6)
		(legacy_teardrops no)
	)
	(paper "A4")
	(title_block
		(title "03242023_DA0F0TMBIJ0_F0T_Motherboard_J_brd_V01_OCP.brd")
		(comment 1 "Grand Teton / footprints 4127-4128 of 6105")
	)
	(layers
		(0 "F.Cu" signal "TOP")
		(4 "In1.Cu" signal "GND")
		(6 "In2.Cu" signal "IN1")
		(8 "In3.Cu" signal "GND1")
		(10 "In4.Cu" signal "IN2")
		(12 "In5.Cu" signal "GND2")
		(14 "In6.Cu" signal "IN3")
		(16 "In7.Cu" signal "GND3")
		(18 "In8.Cu" signal "VCC")
		(20 "In9.Cu" signal "VCC1")
		(22 "In10.Cu" signal "GND4")
		(24 "In11.Cu" signal "IN4")
		(26 "In12.Cu" signal "GND5")
		(28 "In13.Cu" signal "IN5")
		(30 "In14.Cu" signal "GND6")
		(32 "In15.Cu" signal "IN6")
		(34 "In16.Cu" signal "GND7")
		(2 "B.Cu" signal "BOTTOM")
		(9 "F.Adhes" user "F.Adhesive")
		(11 "B.Adhes" user "B.Adhesive")
		(13 "F.Paste" user "Package Geometry/Pastemask Top")
		(15 "B.Paste" user "Package Geometry/Pastemask Bottom")
		(5 "F.SilkS" user "Ref Des/Silkscreen Top")
		(7 "B.SilkS" user "Ref Des/Silkscreen Bottom")
		(1 "F.Mask" user "Board Geometry/Soldermask Top")
		(3 "B.Mask" user "Board Geometry/Soldermask Bottom")
		(17 "Dwgs.User" user "User.Drawings")
		(19 "Cmts.User" user "User.Comments")
		(21 "Eco1.User" user "User.Eco1")
		(23 "Eco2.User" user "User.Eco2")
		(25 "Edge.Cuts" user "Board Geometry/Outline")
		(27 "Margin" user)
		(31 "F.CrtYd" user "Package Geometry/Place Bound Top")
		(29 "B.CrtYd" user "Package Geometry/Place Bound Bottom")
		(35 "F.Fab" user "Ref Des/Assembly Top")
		(33 "B.Fab" user "Ref Des/Assembly Bottom")
	)
	(footprint ""
		(layer "F.Cu")
		(at 282.452826 -19.699986 180)
		(property "Reference" "R3182"
			(at 0 0 180)
			(layer "F.SilkS")
			(hide yes)
			(effects
				(font
					(size 1.27 1.27)
				)
			)
		)
		(property "Value" ""
			(at 0 0 180)
			(layer "F.Fab")
			(effects
				(font
					(size 1.27 1.27)
				)
			)
		)
		(duplicate_pad_numbers_are_jumpers no)
		(fp_line
			(start 0.7874 0.4064)
			(end -0.7874 0.4064)
			(stroke
				(width 0.1524)
				(type default)
			)
			(layer "F.SilkS")
		)
		(fp_line
			(start 0.7874 -0.4064)
			(end 0.7874 0.4064)
			(stroke
				(width 0.1524)
				(type default)
			)
			(layer "F.SilkS")
		)
		(fp_line
			(start -0.7874 0.4064)
			(end -0.7874 -0.4064)
			(stroke
				(width 0.1524)
				(type default)
			)
			(layer "F.SilkS")
		)
		(fp_line
			(start -0.7874 -0.4064)
			(end 0.7874 -0.4064)
			(stroke
				(width 0.1524)
				(type default)
			)
			(layer "F.SilkS")
		)
		(fp_line
			(start 0.67945 0.3048)
			(end 0.120396 0.3048)
			(stroke
				(width 0.1)
				(type default)
			)
			(layer "F.Fab")
		)
		(fp_line
			(start 0.67945 -0.3048)
			(end 0.67945 0.3048)
			(stroke
				(width 0.1)
				(type default)
			)
			(layer "F.Fab")
		)
		(fp_line
			(start 0.12065 -0.2794)
			(end 0.12065 -0.3048)
			(stroke
				(width 0.1)
				(type default)
			)
			(layer "F.Fab")
		)
		(fp_line
			(start 0.12065 -0.3048)
			(end 0.67945 -0.3048)
			(stroke
				(width 0.1)
				(type default)
			)
			(layer "F.Fab")
		)
		(fp_line
			(start 0.120396 0.3048)
			(end 0.120396 0.2794)
			(stroke
				(width 0.1)
				(type default)
			)
			(layer "F.Fab")
		)
		(fp_line
			(start 0.120396 0.2794)
			(end -0.12065 0.2794)
			(stroke
				(width 0.1)
				(type default)
			)
			(layer "F.Fab")
		)
		(fp_line
			(start -0.12065 0.3048)
			(end -0.67945 0.3048)
			(stroke
				(width 0.1)
				(type default)
			)
			(layer "F.Fab")
		)
		(fp_line
			(start -0.12065 0.2794)
			(end -0.12065 0.3048)
			(stroke
				(width 0.1)
				(type default)
			)
			(layer "F.Fab")
		)
		(fp_line
			(start -0.12065 -0.2794)
			(end 0.12065 -0.2794)
			(stroke
				(width 0.1)
				(type default)
			)
			(layer "F.Fab")
		)
		(fp_line
			(start -0.12065 -0.305054)
			(end -0.12065 -0.2794)
			(stroke
				(width 0.1)
				(type default)
			)
			(layer "F.Fab")
		)
		(fp_line
			(start -0.67945 0.3048)
			(end -0.67945 -0.305054)
			(stroke
				(width 0.1)
				(type default)
			)
			(layer "F.Fab")
		)
		(fp_line
			(start -0.67945 -0.305054)
			(end -0.12065 -0.305054)
			(stroke
				(width 0.1)
				(type default)
			)
			(layer "F.Fab")
		)
		(pad "1" smd circle
			(at -0.40005 0 180)
			(size 0 0)
			(layers "F.Cu" "F.Mask" "F.Paste")
			(net "P3V3_OCP_V3_2")
		)
		(pad "2" smd circle
			(at 0.40005 0 180)
			(size 0 0)
			(layers "F.Cu" "F.Mask" "F.Paste")
			(net "IRQ_LVC3_OCP_V3_2_WAKE_N")
		)
	)
	(footprint ""
		(layer "F.Cu")
		(at 193.93408 -355.996748 180)
		(property "Reference" "R1004"
			(at 0 0 180)
			(layer "F.SilkS")
			(hide yes)
			(effects
				(font
					(size 1.27 1.27)
				)
			)
		)
		(property "Value" ""
			(at 0 0 180)
			(layer "F.Fab")
			(effects
				(font
					(size 1.27 1.27)
				)
			)
		)
		(duplicate_pad_numbers_are_jumpers no)
		(fp_line
			(start 0.7874 0.4064)
			(end -0.7874 0.4064)
			(stroke
				(width 0.1524)
				(type default)
			)
			(layer "F.SilkS")
		)
		(fp_line
			(start 0.7874 -0.4064)
			(end 0.7874 0.4064)
			(stroke
				(width 0.1524)
				(type default)
			)
			(layer "F.SilkS")
		)
		(fp_line
			(start -0.7874 0.4064)
			(end -0.7874 -0.4064)
			(stroke
				(width 0.1524)
				(type default)
			)
			(layer "F.SilkS")
		)
		(fp_line
			(start -0.7874 -0.4064)
			(end 0.7874 -0.4064)
			(stroke
				(width 0.1524)
				(type default)
			)
			(layer "F.SilkS")
		)
		(fp_line
			(start 0.67945 0.3048)
			(end 0.120396 0.3048)
			(stroke
				(width 0.1)
				(type default)
			)
			(layer "F.Fab")
		)
		(fp_line
			(start 0.67945 -0.3048)
			(end 0.67945 0.3048)
			(stroke
				(width 0.1)
				(type default)
			)
			(layer "F.Fab")
		)
		(fp_line
			(start 0.12065 -0.2794)
			(end 0.12065 -0.3048)
			(stroke
				(width 0.1)
				(type default)
			)
			(layer "F.Fab")
		)
		(fp_line
			(start 0.12065 -0.3048)
			(end 0.67945 -0.3048)
			(stroke
				(width 0.1)
				(type default)
			)
			(layer "F.Fab")
		)
		(fp_line
			(start 0.120396 0.3048)
			(end 0.120396 0.2794)
			(stroke
				(width 0.1)
				(type default)
			)
			(layer "F.Fab")
		)
		(fp_line
			(start 0.120396 0.2794)
			(end -0.12065 0.2794)
			(stroke
				(width 0.1)
				(type default)
			)
			(layer "F.Fab")
		)
		(fp_line
			(start -0.12065 0.3048)
			(end -0.67945 0.3048)
			(stroke
				(width 0.1)
				(type default)
			)
			(layer "F.Fab")
		)
		(fp_line
			(start -0.12065 0.2794)
			(end -0.12065 0.3048)
			(stroke
				(width 0.1)
				(type default)
			)
			(layer "F.Fab")
		)
		(fp_line
			(start -0.12065 -0.2794)
			(end 0.12065 -0.2794)
			(stroke
				(width 0.1)
				(type default)
			)
			(layer "F.Fab")
		)
		(fp_line
			(start -0.12065 -0.305054)
			(end -0.12065 -0.2794)
			(stroke
				(width 0.1)
				(type default)
			)
			(layer "F.Fab")
		)
		(fp_line
			(start -0.67945 0.3048)
			(end -0.67945 -0.305054)
			(stroke
				(width 0.1)
				(type default)
			)
			(layer "F.Fab")
		)
		(fp_line
			(start -0.67945 -0.305054)
			(end -0.12065 -0.305054)
			(stroke
				(width 0.1)
				(type default)
			)
			(layer "F.Fab")
		)
		(pad "1" smd circle
			(at -0.40005 0 180)
			(size 0 0)
			(layers "F.Cu" "F.Mask" "F.Paste")
			(net "P3V3_AUX")
		)
		(pad "2" smd circle
			(at 0.40005 0 180)
			(size 0 0)
			(layers "F.Cu" "F.Mask" "F.Paste")
			(net "PU_PIROM_CPU1_SM_WP")
		)
	)
)
